# T6G (Grand Teton) — schematic netlist excerpt (pin names and nets, part order shuffled) for the footprints in the layout excerpt that follows; sources: Cadence DE-HDL packaged netlist, KiCad conversion of 04192023_DAF0TMB3IC0_F0TG_MB_C_brd_V02_OCP.brd

R1254  Q_RES  0 5% CHIP  pkg 0402LF  page 258 : A = PVDD18_S5_P0_ADC ; B = PVDD18_S5_P0_ADC_TIC
C8015  Q_CAP  100NF 50V 10% EMPTY  pkg C0402  page 267 : A = HSC_OC_VOL ; B = GND

(kicad_pcb
	(version 20260206)
	(generator "pcbnew")
	(generator_version "10.0")
	(general
		(thickness 1.6)
		(legacy_teardrops no)
	)
	(paper "A4")
	(title_block
		(title "04192023_DAF0TMB3IC0_F0TG_MB_C_brd_V02_OCP.brd")
		(comment 1 "Grand Teton / footprints 5956-5957 of 8354")
	)
	(layers
		(0 "F.Cu" signal "TOP")
		(4 "In1.Cu" signal "GND")
		(6 "In2.Cu" signal "IN1")
		(8 "In3.Cu" signal "GND1")
		(10 "In4.Cu" signal "IN2")
		(12 "In5.Cu" signal "GND2")
		(14 "In6.Cu" signal "IN3")
		(16 "In7.Cu" signal "GND3")
		(18 "In8.Cu" signal "VCC")
		(20 "In9.Cu" signal "VCC1")
		(22 "In10.Cu" signal "GND4")
		(24 "In11.Cu" signal "IN4")
		(26 "In12.Cu" signal "GND5")
		(28 "In13.Cu" signal "IN5")
		(30 "In14.Cu" signal "GND6")
		(32 "In15.Cu" signal "IN6")
		(34 "In16.Cu" signal "GND7")
		(2 "B.Cu" signal "BOTTOM")
		(9 "F.Adhes" user "F.Adhesive")
		(11 "B.Adhes" user "B.Adhesive")
		(13 "F.Paste" user "Package Geometry/Pastemask Top")
		(15 "B.Paste" user "Package Geometry/Pastemask Bottom")
		(5 "F.SilkS" user "Ref Des/Silkscreen Top")
		(7 "B.SilkS" user "Ref Des/Silkscreen Bottom")
		(1 "F.Mask" user "Board Geometry/Soldermask Top")
		(3 "B.Mask" user "Board Geometry/Soldermask Bottom")
		(17 "Dwgs.User" user "User.Drawings")
		(19 "Cmts.User" user "User.Comments")
		(21 "Eco1.User" user "User.Eco1")
		(23 "Eco2.User" user "User.Eco2")
		(25 "Edge.Cuts" user "Board Geometry/Outline")
		(27 "Margin" user)
		(31 "F.CrtYd" user "Package Geometry/Place Bound Top")
		(29 "B.CrtYd" user "Package Geometry/Place Bound Bottom")
		(35 "F.Fab" user "Ref Des/Assembly Top")
		(33 "B.Fab" user "Ref Des/Assembly Bottom")
	)
	(footprint ""
		(layer "B.Cu")
		(at 184.480708 -422.208452 90)
		(property "Reference" "C8015"
			(at 0 0 90)
			(layer "B.SilkS")
			(hide yes)
			(effects
				(font
					(size 1.27 1.27)
				)
				(justify mirror)
			)
		)
		(property "Value" ""
			(at 0 0 90)
			(layer "B.Fab")
			(effects
				(font
					(size 1.27 1.27)
				)
				(justify mirror)
			)
		)
		(duplicate_pad_numbers_are_jumpers no)
		(fp_line
			(start 0.7874 -0.4064)
			(end -0.7874 -0.4064)
			(stroke
				(width 0.1524)
				(type default)
			)
			(layer "B.SilkS")
		)
		(fp_line
			(start -0.7874 -0.4064)
			(end -0.7874 0.4064)
			(stroke
				(width 0.1524)
				(type default)
			)
			(layer "B.SilkS")
		)
		(fp_line
			(start 0.7874 0.4064)
			(end 0.7874 -0.4064)
			(stroke
				(width 0.1524)
				(type default)
			)
			(layer "B.SilkS")
		)
		(fp_line
			(start -0.7874 0.4064)
			(end 0.7874 0.4064)
			(stroke
				(width 0.1524)
				(type default)
			)
			(layer "B.SilkS")
		)
		(fp_line
			(start 0.67945 -0.305054)
			(end 0.12065 -0.305054)
			(stroke
				(width 0.1)
				(type default)
			)
			(layer "B.Fab")
		)
		(fp_line
			(start 0.12065 -0.305054)
			(end 0.12065 -0.2794)
			(stroke
				(width 0.1)
				(type default)
			)
			(layer "B.Fab")
		)
		(fp_line
			(start -0.12065 -0.3048)
			(end -0.67945 -0.3048)
			(stroke
				(width 0.1)
				(type default)
			)
			(layer "B.Fab")
		)
		(fp_line
			(start -0.67945 -0.3048)
			(end -0.67945 0.3048)
			(stroke
				(width 0.1)
				(type default)
			)
			(layer "B.Fab")
		)
		(fp_line
			(start 0.12065 -0.2794)
			(end -0.12065 -0.2794)
			(stroke
				(width 0.1)
				(type default)
			)
			(layer "B.Fab")
		)
		(fp_line
			(start -0.12065 -0.2794)
			(end -0.12065 -0.3048)
			(stroke
				(width 0.1)
				(type default)
			)
			(layer "B.Fab")
		)
		(fp_line
			(start 0.12065 0.2794)
			(end 0.12065 0.3048)
			(stroke
				(width 0.1)
				(type default)
			)
			(layer "B.Fab")
		)
		(fp_line
			(start -0.120396 0.2794)
			(end 0.12065 0.2794)
			(stroke
				(width 0.1)
				(type default)
			)
			(layer "B.Fab")
		)
		(fp_line
			(start 0.67945 0.3048)
			(end 0.67945 -0.305054)
			(stroke
				(width 0.1)
				(type default)
			)
			(layer "B.Fab")
		)
		(fp_line
			(start 0.12065 0.3048)
			(end 0.67945 0.3048)
			(stroke
				(width 0.1)
				(type default)
			)
			(layer "B.Fab")
		)
		(fp_line
			(start -0.120396 0.3048)
			(end -0.120396 0.2794)
			(stroke
				(width 0.1)
				(type default)
			)
			(layer "B.Fab")
		)
		(fp_line
			(start -0.67945 0.3048)
			(end -0.120396 0.3048)
			(stroke
				(width 0.1)
				(type default)
			)
			(layer "B.Fab")
		)
		(pad "1" smd circle
			(at 0.40005 0 270)
			(size 0 0)
			(layers "B.Cu" "B.Mask" "B.Paste")
			(net "HSC_OC_VOL")
		)
		(pad "2" smd circle
			(at -0.40005 0 270)
			(size 0 0)
			(layers "B.Cu" "B.Mask" "B.Paste")
			(net "GND")
		)
	)
	(footprint ""
		(layer "B.Cu")
		(at 231.034082 -328.25182)
		(property "Reference" "R1254"
			(at 0 0 0)
			(layer "B.SilkS")
			(hide yes)
			(effects
				(font
					(size 1.27 1.27)
				)
				(justify mirror)
			)
		)
		(property "Value" ""
			(at 0 0 0)
			(layer "B.Fab")
			(effects
				(font
					(size 1.27 1.27)
				)
				(justify mirror)
			)
		)
		(duplicate_pad_numbers_are_jumpers no)
		(fp_line
			(start -0.7874 -0.4064)
			(end -0.7874 0.4064)
			(stroke
				(width 0.1524)
				(type default)
			)
			(layer "B.SilkS")
		)
		(fp_line
			(start -0.7874 0.4064)
			(end 0.7874 0.4064)
			(stroke
				(width 0.1524)
				(type default)
			)
			(layer "B.SilkS")
		)
		(fp_line
			(start 0.7874 -0.4064)
			(end -0.7874 -0.4064)
			(stroke
				(width 0.1524)
				(type default)
			)
			(layer "B.SilkS")
		)
		(fp_line
			(start 0.7874 0.4064)
			(end 0.7874 -0.4064)
			(stroke
				(width 0.1524)
				(type default)
			)
			(layer "B.SilkS")
		)
		(fp_line
			(start -0.67945 -0.3048)
			(end -0.67945 0.3048)
			(stroke
				(width 0.1)
				(type default)
			)
			(layer "B.Fab")
		)
		(fp_line
			(start -0.67945 0.3048)
			(end -0.120396 0.3048)
			(stroke
				(width 0.1)
				(type default)
			)
			(layer "B.Fab")
		)
		(fp_line
			(start -0.12065 -0.3048)
			(end -0.67945 -0.3048)
			(stroke
				(width 0.1)
				(type default)
			)
			(layer "B.Fab")
		)
		(fp_line
			(start -0.12065 -0.2794)
			(end -0.12065 -0.3048)
			(stroke
				(width 0.1)
				(type default)
			)
			(layer "B.Fab")
		)
		(fp_line
			(start -0.120396 0.2794)
			(end 0.12065 0.2794)
			(stroke
				(width 0.1)
				(type default)
			)
			(layer "B.Fab")
		)
		(fp_line
			(start -0.120396 0.3048)
			(end -0.120396 0.2794)
			(stroke
				(width 0.1)
				(type default)
			)
			(layer "B.Fab")
		)
		(fp_line
			(start 0.12065 -0.305054)
			(end 0.12065 -0.2794)
			(stroke
				(width 0.1)
				(type default)
			)
			(layer "B.Fab")
		)
		(fp_line
			(start 0.12065 -0.2794)
			(end -0.12065 -0.2794)
			(stroke
				(width 0.1)
				(type default)
			)
			(layer "B.Fab")
		)
		(fp_line
			(start 0.12065 0.2794)
			(end 0.12065 0.3048)
			(stroke
				(width 0.1)
				(type default)
			)
			(layer "B.Fab")
		)
		(fp_line
			(start 0.12065 0.3048)
			(end 0.67945 0.3048)
			(stroke
				(width 0.1)
				(type default)
			)
			(layer "B.Fab")
		)
		(fp_line
			(start 0.67945 -0.305054)
			(end 0.12065 -0.305054)
			(stroke
				(width 0.1)
				(type default)
			)
			(layer "B.Fab")
		)
		(fp_line
			(start 0.67945 0.3048)
			(end 0.67945 -0.305054)
			(stroke
				(width 0.1)
				(type default)
			)
			(layer "B.Fab")
		)
		(pad "1" smd rect
			(at 0.40005 0)
			(size 0.4572 0.508)
			(layers "B.Cu" "B.Mask" "B.Paste")
			(net "PVDD18_S5_P0_ADC")
		)
		(pad "2" smd rect
			(at -0.40005 0)
			(size 0.4572 0.508)
			(layers "B.Cu" "B.Mask" "B.Paste")
			(net "PVDD18_S5_P0_ADC_TIC")
		)
	)
)
